# BASEBOARD_FAB2 (Tioga Pass) — schematic netlist excerpt (pin names and nets, part order shuffled) for the footprints in the layout excerpt that follows; sources: Cadence DE-HDL packaged netlist, KiCad conversion of Wiwynn_Tioga_Pass_MB.brd

R3R13  RES  240 1.0% CHIP  pkg 0402  page 99 : A = PVCCIO_CPU0 ; B = SMB_DDR_DEF_SDA_G

Q4W2  FET_N  2N7002 FET  pkg SOT23LF  page 102
  GATE  = FM_DB1200_PWRGD
  SRC  = GND
  DRN  = FM_DB1200_PWRGD_R

C5M7  CAP_A  47UF 4V 20% X5R  pkg 0603V  page 220 : A = PVDDQ_DEF ; B = GND

(kicad_pcb
	(version 20260206)
	(generator "pcbnew")
	(generator_version "10.0")
	(general
		(thickness 1.6)
		(legacy_teardrops no)
	)
	(paper "A4")
	(title_block
		(title "Wiwynn_Tioga_Pass_MB.brd")
		(comment 1 "Tioga Pass / footprints 3074-3076 of 4770")
	)
	(layers
		(0 "F.Cu" signal "TOP")
		(4 "In1.Cu" signal "L2GND")
		(6 "In2.Cu" signal "L3")
		(8 "In3.Cu" signal "L4GND")
		(10 "In4.Cu" signal "L5")
		(12 "In5.Cu" signal "L6GND")
		(14 "In6.Cu" signal "L7VCC")
		(16 "In7.Cu" signal "L8VCC")
		(18 "In8.Cu" signal "L9GND")
		(20 "In9.Cu" signal "L10")
		(22 "In10.Cu" signal "L11GND")
		(24 "In11.Cu" signal "L12")
		(26 "In12.Cu" signal "L13GND")
		(2 "B.Cu" signal "BOTTOM")
		(9 "F.Adhes" user "F.Adhesive")
		(11 "B.Adhes" user "B.Adhesive")
		(13 "F.Paste" user "Package Geometry/Pastemask Top")
		(15 "B.Paste" user "Package Geometry/Pastemask Bottom")
		(5 "F.SilkS" user "Ref Des/Silkscreen Top")
		(7 "B.SilkS" user "Ref Des/Silkscreen Bottom")
		(1 "F.Mask" user "Board Geometry/Soldermask Top")
		(3 "B.Mask" user "Board Geometry/Soldermask Bottom")
		(17 "Dwgs.User" user "User.Drawings")
		(19 "Cmts.User" user "User.Comments")
		(21 "Eco1.User" user "User.Eco1")
		(23 "Eco2.User" user "User.Eco2")
		(25 "Edge.Cuts" user "Board Geometry/Outline")
		(27 "Margin" user)
		(31 "F.CrtYd" user "Package Geometry/Place Bound Top")
		(29 "B.CrtYd" user "Package Geometry/Place Bound Bottom")
		(35 "F.Fab" user "Ref Des/Assembly Top")
		(33 "B.Fab" user "Ref Des/Assembly Bottom")
	)
	(footprint ""
		(layer "B.Cu")
		(at 330.091288 -64.17564 90)
		(property "Reference" "R3R13"
			(at 0 0 90)
			(layer "B.SilkS")
			(hide yes)
			(effects
				(font
					(size 1.27 1.27)
				)
				(justify mirror)
			)
		)
		(property "Value" ""
			(at 0 0 90)
			(layer "B.Fab")
			(effects
				(font
					(size 1.27 1.27)
				)
				(justify mirror)
			)
		)
		(duplicate_pad_numbers_are_jumpers no)
		(fp_poly
			(pts
				(xy 0.2794 -0.1016) (xy -0.2794 -0.1016) (xy -0.2794 0.9906) (xy 0.2794 0.9906)
			)
			(stroke
				(width 0)
				(type default)
			)
			(fill no)
			(layer "B.CrtYd")
		)
		(fp_line
			(start 0.2794 -0.1016)
			(end 0.2794 0.9906)
			(stroke
				(width 0.1)
				(type default)
			)
			(layer "B.Fab")
		)
		(fp_line
			(start -0.2794 -0.1016)
			(end 0.2794 -0.1016)
			(stroke
				(width 0.1)
				(type default)
			)
			(layer "B.Fab")
		)
		(fp_line
			(start 0.2794 0.9906)
			(end -0.2794 0.9906)
			(stroke
				(width 0.1)
				(type default)
			)
			(layer "B.Fab")
		)
		(fp_line
			(start -0.2794 0.9906)
			(end -0.2794 -0.1016)
			(stroke
				(width 0.1)
				(type default)
			)
			(layer "B.Fab")
		)
		(pad "1" smd rect
			(at 0 0 270)
			(size 0.508 0.508)
			(layers "B.Cu" "B.Mask" "B.Paste")
			(net "PVCCIO_CPU0")
		)
		(pad "2" smd rect
			(at 0 0.889 270)
			(size 0.508 0.508)
			(layers "B.Cu" "B.Mask" "B.Paste")
			(net "SMB_DDR_DEF_SDA_G")
		)
		(zone
			(layer "B.Cu")
			(hatch none 0.5)
			(connect_pads
				(clearance 0)
			)
			(min_thickness 0.25)
			(keepout
				(tracks allowed)
				(vias not_allowed)
				(pads allowed)
				(copperpour not_allowed)
				(footprints allowed)
			)
			(placement
				(enabled no)
				(sheetname "")
			)
			(fill
				(thermal_gap 0.5)
				(thermal_bridge_width 0.5)
				(island_removal_mode 0)
			)
			(polygon
				(pts
					(xy 330.345288 -64.42964) (xy 330.345288 -63.92164) (xy 330.726288 -63.92164) (xy 330.726288 -64.42964)
				)
			)
		)
		(zone
			(layer "B.Cu")
			(hatch none 0.5)
			(connect_pads
				(clearance 0)
			)
			(min_thickness 0.25)
			(keepout
				(tracks not_allowed)
				(vias allowed)
				(pads allowed)
				(copperpour not_allowed)
				(footprints allowed)
			)
			(placement
				(enabled no)
				(sheetname "")
			)
			(fill
				(thermal_gap 0.5)
				(thermal_bridge_width 0.5)
				(island_removal_mode 0)
			)
			(polygon
				(pts
					(xy 330.726288 -64.42964) (xy 330.726288 -63.92164) (xy 330.345288 -63.92164) (xy 330.345288 -64.42964)
				)
			)
		)
	)
	(footprint ""
		(layer "B.Cu")
		(at 173.279816 -68.650104 180)
		(property "Reference" "Q4W2"
			(at 0.229362 -1.59512 180)
			(unlocked yes)
			(layer "B.SilkS")
			(effects
				(font
					(size 1.27 0.9652)
					(thickness 0.1524)
				)
				(justify left mirror)
			)
		)
		(property "Value" ""
			(at 0 0 0)
			(layer "B.Fab")
			(effects
				(font
					(size 1.27 1.27)
				)
				(justify mirror)
			)
		)
		(duplicate_pad_numbers_are_jumpers no)
		(fp_line
			(start -0.381 0.635)
			(end -0.381 1.27)
			(stroke
				(width 0.1524)
				(type default)
			)
			(layer "B.SilkS")
		)
		(fp_line
			(start -0.9525 2.4765)
			(end -1.778 2.4765)
			(stroke
				(width 0.1524)
				(type default)
			)
			(layer "B.SilkS")
		)
		(fp_line
			(start -0.9525 -0.5715)
			(end -1.778 -0.5715)
			(stroke
				(width 0.1524)
				(type default)
			)
			(layer "B.SilkS")
		)
		(fp_line
			(start -1.778 2.4765)
			(end -1.778 1.5875)
			(stroke
				(width 0.1524)
				(type default)
			)
			(layer "B.SilkS")
		)
		(fp_line
			(start -1.778 -0.5715)
			(end -1.778 0.3175)
			(stroke
				(width 0.1524)
				(type default)
			)
			(layer "B.SilkS")
		)
		(fp_circle
			(center 0.9525 -0.9271)
			(end 0.8255 -0.9271)
			(stroke
				(width 0.254)
				(type default)
			)
			(fill no)
			(layer "B.SilkS")
		)
		(fp_poly
			(pts
				(xy -1.778 2.4765) (xy -0.381 2.4765) (xy -0.381 -0.5715) (xy -1.778 -0.5715)
			)
			(stroke
				(width 0)
				(type default)
			)
			(fill no)
			(layer "B.CrtYd")
		)
		(fp_line
			(start -0.381 2.4765)
			(end -1.778 2.4765)
			(stroke
				(width 0.1)
				(type default)
			)
			(layer "B.Fab")
		)
		(fp_line
			(start -0.381 -0.5715)
			(end -0.381 2.4765)
			(stroke
				(width 0.1)
				(type default)
			)
			(layer "B.Fab")
		)
		(fp_line
			(start -1.778 2.4765)
			(end -1.778 -0.5715)
			(stroke
				(width 0.1)
				(type default)
			)
			(layer "B.Fab")
		)
		(fp_line
			(start -1.778 -0.5715)
			(end -0.381 -0.5715)
			(stroke
				(width 0.1)
				(type default)
			)
			(layer "B.Fab")
		)
		(fp_circle
			(center 0.9525 -0.9271)
			(end 0.8255 -0.9271)
			(stroke
				(width 0.254)
				(type default)
			)
			(fill no)
			(layer "B.Fab")
		)
		(pad "1" smd rect
			(at 0 0)
			(size 1.143 0.508)
			(layers "B.Cu" "B.Mask" "B.Paste")
			(net "FM_DB1200_PWRGD")
		)
		(pad "2" smd rect
			(at 0 1.905)
			(size 1.143 0.508)
			(layers "B.Cu" "B.Mask" "B.Paste")
			(net "GND")
		)
		(pad "3" smd rect
			(at -2.159 0.9525)
			(size 1.143 0.508)
			(layers "B.Cu" "B.Mask" "B.Paste")
			(net "FM_DB1200_PWRGD_R")
		)
	)
	(footprint ""
		(layer "B.Cu")
		(at 245.7577 -135.4074 -90)
		(property "Reference" "C5M7"
			(at -1.848866 0.752348 270)
			(unlocked yes)
			(layer "B.SilkS")
			(effects
				(font
					(size 1.27 0.9652)
					(thickness 0.1524)
				)
				(justify mirror)
			)
		)
		(property "Value" ""
			(at 0 0 90)
			(layer "B.Fab")
			(effects
				(font
					(size 1.27 1.27)
				)
				(justify mirror)
			)
		)
		(duplicate_pad_numbers_are_jumpers no)
		(fp_rect
			(start 0.500126 1.598422)
			(end -0.500126 -0.201422)
			(stroke
				(width 0)
				(type default)
			)
			(fill no)
			(layer "B.CrtYd")
		)
		(fp_line
			(start -0.500126 1.598422)
			(end 0.500126 1.598422)
			(stroke
				(width 0.1)
				(type default)
			)
			(layer "B.Fab")
		)
		(fp_line
			(start 0.500126 1.598422)
			(end 0.500126 -0.201422)
			(stroke
				(width 0.1)
				(type default)
			)
			(layer "B.Fab")
		)
		(fp_line
			(start -0.500126 -0.201422)
			(end -0.500126 1.598422)
			(stroke
				(width 0.1)
				(type default)
			)
			(layer "B.Fab")
		)
		(fp_line
			(start 0.500126 -0.201422)
			(end -0.500126 -0.201422)
			(stroke
				(width 0.1)
				(type default)
			)
			(layer "B.Fab")
		)
		(pad "1" smd rect
			(at 0 0 180)
			(size 0.889 0.9906)
			(layers "B.Cu" "B.Mask" "B.Paste")
			(net "PVDDQ_DEF")
		)
		(pad "2" smd rect
			(at 0 1.397 180)
			(size 0.889 0.9906)
			(layers "B.Cu" "B.Mask" "B.Paste")
			(net "GND")
		)
		(zone
			(layer "B.Cu")
			(hatch none 0.5)
			(connect_pads
				(clearance 0)
			)
			(min_thickness 0.25)
			(keepout
				(tracks not_allowed)
				(vias allowed)
				(pads allowed)
				(copperpour not_allowed)
				(footprints allowed)
			)
			(placement
				(enabled no)
				(sheetname "")
			)
			(fill
				(thermal_gap 0.5)
				(thermal_bridge_width 0.5)
				(island_removal_mode 0)
			)
			(polygon
				(pts
					(xy 244.8052 -134.9121) (xy 245.3132 -134.9121) (xy 245.3132 -135.9027) (xy 244.8052 -135.9027)
				)
			)
		)
		(zone
			(layer "B.Cu")
			(hatch none 0.5)
			(connect_pads
				(clearance 0)
			)
			(min_thickness 0.25)
			(keepout
				(tracks allowed)
				(vias not_allowed)
				(pads allowed)
				(copperpour not_allowed)
				(footprints allowed)
			)
			(placement
				(enabled no)
				(sheetname "")
			)
			(fill
				(thermal_gap 0.5)
				(thermal_bridge_width 0.5)
				(island_removal_mode 0)
			)
			(polygon
				(pts
					(xy 244.8052 -134.9121) (xy 245.3132 -134.9121) (xy 245.3132 -135.9027) (xy 244.8052 -135.9027)
				)
			)
		)
	)
)
